(kicad_pcb
	(version 20260206)
	(generator "pcbnew")
	(generator_version "10.0")
	(general
		(thickness 1.6)
		(legacy_teardrops no)
	)
	(paper "A4")
	(title_block
		(title "Bryce Canyon_Front Panel_16369-1_OCP.brd")
		(comment 1 "Bryce Canyon / footprints 99-102 of 154")
	)
	(layers
		(0 "F.Cu" signal "TOP")
		(4 "In1.Cu" signal "L2GND")
		(6 "In2.Cu" signal "L3VCC")
		(2 "B.Cu" signal "BOTTOM")
		(9 "F.Adhes" user "F.Adhesive")
		(11 "B.Adhes" user "B.Adhesive")
		(13 "F.Paste" user "Package Geometry/Pastemask Top")
		(15 "B.Paste" user "Package Geometry/Pastemask Bottom")
		(5 "F.SilkS" user "Ref Des/Silkscreen Top")
		(7 "B.SilkS" user "Ref Des/Silkscreen Bottom")
		(1 "F.Mask" user "Board Geometry/Soldermask Top")
		(3 "B.Mask" user "Board Geometry/Soldermask Bottom")
		(17 "Dwgs.User" user "User.Drawings")
		(19 "Cmts.User" user "User.Comments")
		(21 "Eco1.User" user "User.Eco1")
		(23 "Eco2.User" user "User.Eco2")
		(25 "Edge.Cuts" user "Board Geometry/Outline")
		(27 "Margin" user)
		(31 "F.CrtYd" user "Package Geometry/Place Bound Top")
		(29 "B.CrtYd" user "Package Geometry/Place Bound Bottom")
		(35 "F.Fab" user "Ref Des/Assembly Top")
		(33 "B.Fab" user "Ref Des/Assembly Bottom")
	)
	(footprint ""
		(layer "F.Cu")
		(at 8.199882 -59.99988 90)
		(property "Reference" "USB1"
			(at 0 0 90)
			(layer "F.SilkS")
			(hide yes)
			(effects
				(font
					(size 1.27 1.27)
				)
			)
		)
		(property "Value" "SKT-USB13-208-GP"
			(at -9.1821 -7.5692 90)
			(unlocked yes)
			(layer "F.Fab")
			(hide yes)
			(effects
				(font
					(size 1.016 1.016)
					(thickness 0.1524)
				)
			)
		)
		(property "Device Type" "SKT-USB13-148074-5"
			(at -9.1821 -9.0932 90)
			(unlocked yes)
			(layer "F.Fab")
			(hide yes)
			(effects
				(font
					(size 1.016 1.016)
					(thickness 0.1524)
				)
			)
		)
		(duplicate_pad_numbers_are_jumpers no)
		(fp_line
			(start 8.0137 -3.9497)
			(end 8.0137 3.9497)
			(stroke
				(width 0.1524)
				(type default)
			)
			(layer "F.SilkS")
		)
		(fp_line
			(start -8.0137 -3.9497)
			(end 8.0137 -3.9497)
			(stroke
				(width 0.1524)
				(type default)
			)
			(layer "F.SilkS")
		)
		(fp_line
			(start 8.0137 3.9497)
			(end -8.0137 3.9497)
			(stroke
				(width 0.1524)
				(type default)
			)
			(layer "F.SilkS")
		)
		(fp_line
			(start -8.0137 3.9497)
			(end -8.0137 -3.9497)
			(stroke
				(width 0.1524)
				(type default)
			)
			(layer "F.SilkS")
		)
		(fp_arc
			(start 4.854956 1.256792)
			(mid 8.078491 2.349096)
			(end 4.686808 2.064512)
			(stroke
				(width 0.3048)
				(type default)
			)
			(layer "F.SilkS")
		)
		(fp_arc
			(start -4.854956 1.256792)
			(mid -3.12974 1.318917)
			(end -4.686808 2.064512)
			(stroke
				(width 0.3048)
				(type default)
			)
			(layer "F.SilkS")
		)
		(fp_arc
			(start 4.686808 2.064512)
			(mid 3.129699 1.318908)
			(end 4.854956 1.256792)
			(stroke
				(width 0.3048)
				(type default)
			)
			(layer "F.SilkS")
		)
		(fp_arc
			(start -4.686808 2.064512)
			(mid -8.078519 2.349102)
			(end -4.854956 1.256792)
			(stroke
				(width 0.3048)
				(type default)
			)
			(layer "F.SilkS")
		)
		(fp_circle
			(center 6.400038 -1.999996)
			(end 6.400038 -0.285496)
			(stroke
				(width 0.3048)
				(type default)
			)
			(fill no)
			(layer "F.SilkS")
		)
		(fp_circle
			(center -6.400038 -1.999996)
			(end -6.400038 -0.285496)
			(stroke
				(width 0.3048)
				(type default)
			)
			(fill no)
			(layer "F.SilkS")
		)
		(fp_circle
			(center 3.50012 -0.999998)
			(end 3.50012 -0.110998)
			(stroke
				(width 0.3048)
				(type default)
			)
			(fill no)
			(layer "F.SilkS")
		)
		(fp_circle
			(center 0.999998 -0.999998)
			(end 0.999998 -0.110998)
			(stroke
				(width 0.3048)
				(type default)
			)
			(fill no)
			(layer "F.SilkS")
		)
		(fp_circle
			(center -0.999998 -0.999998)
			(end -0.999998 -0.110998)
			(stroke
				(width 0.3048)
				(type default)
			)
			(fill no)
			(layer "F.SilkS")
		)
		(fp_circle
			(center -3.50012 -0.999998)
			(end -3.50012 -0.110998)
			(stroke
				(width 0.3048)
				(type default)
			)
			(fill no)
			(layer "F.SilkS")
		)
		(fp_circle
			(center 1.999996 1.500124)
			(end 1.999996 2.389124)
			(stroke
				(width 0.3048)
				(type default)
			)
			(fill no)
			(layer "F.SilkS")
		)
		(fp_circle
			(center 0 1.500124)
			(end 0 2.389124)
			(stroke
				(width 0.3048)
				(type default)
			)
			(fill no)
			(layer "F.SilkS")
		)
		(fp_circle
			(center -1.999996 1.500124)
			(end -1.999996 2.389124)
			(stroke
				(width 0.3048)
				(type default)
			)
			(fill no)
			(layer "F.SilkS")
		)
		(fp_rect
			(start -7.4041 3.6957)
			(end 7.4041 -3.6957)
			(stroke
				(width 0)
				(type default)
			)
			(fill no)
			(layer "F.CrtYd")
		)
		(fp_poly
			(pts
				(xy -8.2677 4.2037) (xy -8.2677 -4.2037) (xy 8.2677 -4.2037) (xy 8.2677 -0.00635) (xy 7.4041 -0.00635)
				(xy 7.4041 -3.6957) (xy -7.4041 -3.6957) (xy -7.4041 3.6957) (xy 7.4041 3.6957) (xy 7.4041 0.00635)
				(xy 8.2677 0.00635) (xy 8.2677 4.2037)
			)
			(stroke
				(width 0)
				(type default)
			)
			(fill no)
			(layer "F.CrtYd")
		)
		(fp_rect
			(start -8.2677 4.2037)
			(end 8.2677 -4.2037)
			(stroke
				(width 0)
				(type default)
			)
			(fill no)
			(layer "F.Fab")
		)
		(pad "1" thru_hole circle
			(at 3.50012 -0.999998 90)
			(size 1.0668 1.0668)
			(drill 0.7112)
			(layers "*.Cu" "*.Mask")
			(remove_unused_layers no)
			(net "P5V_VBUS_A")
			(clearance 0.1778)
			(thermal_gap 0.1778)
		)
		(pad "2" thru_hole circle
			(at 0.999998 -0.999998 90)
			(size 1.0668 1.0668)
			(drill 0.7112)
			(layers "*.Cu" "*.Mask")
			(remove_unused_layers no)
			(net "DEBUG_USB_A_DN")
			(clearance 0.1778)
			(thermal_gap 0.1778)
		)
		(pad "3" thru_hole circle
			(at -0.999998 -0.999998 90)
			(size 1.0668 1.0668)
			(drill 0.7112)
			(layers "*.Cu" "*.Mask")
			(remove_unused_layers no)
			(net "DEBUG_USB_A_DP")
			(clearance 0.1778)
			(thermal_gap 0.1778)
		)
		(pad "4" thru_hole circle
			(at -3.50012 -0.999998 90)
			(size 1.0668 1.0668)
			(drill 0.7112)
			(layers "*.Cu" "*.Mask")
			(remove_unused_layers no)
			(net "GND")
			(clearance 0.1778)
			(thermal_gap 0.1778)
		)
		(pad "5" thru_hole circle
			(at -3.999992 1.500124 90)
			(size 1.0668 1.0668)
			(drill 0.7112)
			(layers "*.Cu" "*.Mask")
			(remove_unused_layers no)
			(net "I2C_DEBUG_A_SCL")
			(clearance 0.1778)
			(thermal_gap 0.1778)
		)
		(pad "6" thru_hole circle
			(at -1.999996 1.500124 90)
			(size 1.0668 1.0668)
			(drill 0.7112)
			(layers "*.Cu" "*.Mask")
			(remove_unused_layers no)
			(net "I2C_DEBUG_A_SDA")
			(clearance 0.1778)
			(thermal_gap 0.1778)
		)
		(pad "7" thru_hole circle
			(at 0 1.500124 90)
			(size 1.0668 1.0668)
			(drill 0.7112)
			(layers "*.Cu" "*.Mask")
			(remove_unused_layers no)
			(net "DEBUG_CARD_A_PRSNT")
			(clearance 0.1778)
			(thermal_gap 0.1778)
		)
		(pad "8" thru_hole circle
			(at 1.999996 1.500124 90)
			(size 1.0668 1.0668)
			(drill 0.7112)
			(layers "*.Cu" "*.Mask")
			(remove_unused_layers no)
			(net "UART_DEBUG_A_TX")
			(clearance 0.1778)
			(thermal_gap 0.1778)
		)
		(pad "9" thru_hole circle
			(at 3.999992 1.500124 90)
			(size 1.0668 1.0668)
			(drill 0.7112)
			(layers "*.Cu" "*.Mask")
			(remove_unused_layers no)
			(net "UART_DEBUG_A_RX")
			(clearance 0.1778)
			(thermal_gap 0.1778)
		)
		(pad "10" thru_hole circle
			(at 6.400038 -1.999996 90)
			(size 2.7178 2.7178)
			(drill 2.3114)
			(layers "*.Cu" "*.Mask")
			(remove_unused_layers no)
			(net "USB_CONN_A_GND")
			(clearance 0.1524)
			(thermal_gap 0.1524)
		)
		(pad "11" thru_hole circle
			(at -6.400038 -1.999996 90)
			(size 2.7178 2.7178)
			(drill 2.3114)
			(layers "*.Cu" "*.Mask")
			(remove_unused_layers no)
			(net "USB_CONN_A_GND")
			(clearance 0.1524)
			(thermal_gap 0.1524)
		)
		(pad "12" thru_hole circle
			(at 6.400038 1.999996 90)
			(size 2.7178 2.7178)
			(drill 2.3114)
			(layers "*.Cu" "*.Mask")
			(remove_unused_layers no)
			(net "USB_CONN_A_GND")
			(clearance 0.1524)
			(thermal_gap 0.1524)
		)
		(pad "13" thru_hole circle
			(at -6.400038 1.999996 90)
			(size 2.7178 2.7178)
			(drill 2.3114)
			(layers "*.Cu" "*.Mask")
			(remove_unused_layers no)
			(net "USB_CONN_A_GND")
			(clearance 0.1524)
			(thermal_gap 0.1524)
		)
		(zone
			(layer "F.Cu")
			(hatch none 0.5)
			(connect_pads
				(clearance 0)
			)
			(min_thickness 0.25)
			(keepout
				(tracks not_allowed)
				(vias allowed)
				(pads allowed)
				(copperpour not_allowed)
				(footprints allowed)
			)
			(placement
				(enabled no)
				(sheetname "")
			)
			(fill
				(thermal_gap 0.5)
				(thermal_bridge_width 0.5)
				(island_removal_mode 0)
			)
			(polygon
				(pts
					(xy 5.359908 -65.099946) (xy 11.039856 -65.099946) (xy 11.039856 -66.199766) (xy 5.359908 -66.199766)
				)
			)
		)
		(zone
			(layer "F.Cu")
			(hatch none 0.5)
			(connect_pads
				(clearance 0)
			)
			(min_thickness 0.25)
			(keepout
				(tracks not_allowed)
				(vias allowed)
				(pads allowed)
				(copperpour not_allowed)
				(footprints allowed)
			)
			(placement
				(enabled no)
				(sheetname "")
			)
			(fill
				(thermal_gap 0.5)
				(thermal_bridge_width 0.5)
				(island_removal_mode 0)
			)
			(polygon
				(pts
					(xy 5.359908 -53.799994) (xy 11.039856 -53.799994) (xy 11.039856 -54.899814) (xy 5.359908 -54.899814)
				)
			)
		)
		(zone
			(layer "F.Cu")
			(hatch none 0.5)
			(connect_pads
				(clearance 0)
			)
			(min_thickness 0.25)
			(keepout
				(tracks allowed)
				(vias not_allowed)
				(pads allowed)
				(copperpour not_allowed)
				(footprints allowed)
			)
			(placement
				(enabled no)
				(sheetname "")
			)
			(fill
				(thermal_gap 0.5)
				(thermal_bridge_width 0.5)
				(island_removal_mode 0)
			)
			(polygon
				(pts
					(xy 11.039856 -65.099946) (xy 11.039856 -66.199766) (xy 5.359908 -66.199766) (xy 5.359908 -65.099946)
				)
			)
		)
		(zone
			(layer "F.Cu")
			(hatch none 0.5)
			(connect_pads
				(clearance 0)
			)
			(min_thickness 0.25)
			(keepout
				(tracks allowed)
				(vias not_allowed)
				(pads allowed)
				(copperpour not_allowed)
				(footprints allowed)
			)
			(placement
				(enabled no)
				(sheetname "")
			)
			(fill
				(thermal_gap 0.5)
				(thermal_bridge_width 0.5)
				(island_removal_mode 0)
			)
			(polygon
				(pts
					(xy 11.039856 -53.799994) (xy 11.039856 -54.899814) (xy 5.359908 -54.899814) (xy 5.359908 -53.799994)
				)
			)
		)
	)
	(footprint ""
		(layer "F.Cu")
		(at 55.753 -13.9446 180)
		(property "Reference" "R68"
			(at 0 0 180)
			(layer "F.SilkS")
			(hide yes)
			(effects
				(font
					(size 1.27 1.27)
				)
			)
		)
		(property "Value" "4K7R2F-GP"
			(at 0.064008 -3.993896 180)
			(unlocked yes)
			(layer "F.Fab")
			(hide yes)
			(effects
				(font
					(size 1.016 1.016)
					(thickness 0.1524)
				)
			)
		)
		(property "Device Type" "R402H16"
			(at 0.064008 -5.517896 180)
			(unlocked yes)
			(layer "F.Fab")
			(hide yes)
			(effects
				(font
					(size 1.016 1.016)
					(thickness 0.1524)
				)
			)
		)
		(duplicate_pad_numbers_are_jumpers no)
		(fp_line
			(start 0.508 -0.9398)
			(end -0.508 -0.9398)
			(stroke
				(width 0.1524)
				(type default)
			)
			(layer "F.SilkS")
		)
		(fp_line
			(start -0.508 -0.9398)
			(end -0.508 0.9398)
			(stroke
				(width 0.1524)
				(type default)
			)
			(layer "F.SilkS")
		)
		(fp_rect
			(start -0.508 0.9398)
			(end 0.508 -0.9398)
			(stroke
				(width 0)
				(type default)
			)
			(fill no)
			(layer "F.CrtYd")
		)
		(fp_rect
			(start -0.508 0.9398)
			(end 0.508 -0.9398)
			(stroke
				(width 0)
				(type default)
			)
			(fill no)
			(layer "F.Fab")
		)
		(pad "1" smd custom
			(at 0 -0.4445 180)
			(size 0.1397 0.1397)
			(layers "F.Cu" "F.Mask" "F.Paste")
			(net "P3V3_STBY_B")
			(options
				(clearance outline)
				(anchor circle)
			)
			(primitives
				(gr_poly
					(pts
						(arc
							(start -0.1778 -0.2794)
							(mid -0.249642 -0.249642)
							(end -0.2794 -0.1778)
						)
						(arc
							(start -0.2794 0.1778)
							(mid -0.249642 0.249642)
							(end -0.1778 0.2794)
						)
						(arc
							(start 0.1778 0.2794)
							(mid 0.249642 0.249642)
							(end 0.2794 0.1778)
						)
						(arc
							(start 0.2794 -0.1778)
							(mid 0.249642 -0.249642)
							(end 0.1778 -0.2794)
						)
					)
					(width 0)
					(fill yes)
				)
			)
		)
		(pad "2" smd custom
			(at 0 0.4445 180)
			(size 0.1397 0.1397)
			(layers "F.Cu" "F.Mask" "F.Paste")
			(net "IO_EXP_B_RESET#_FLT")
			(options
				(clearance outline)
				(anchor circle)
			)
			(primitives
				(gr_poly
					(pts
						(arc
							(start -0.1778 -0.2794)
							(mid -0.249642 -0.249642)
							(end -0.2794 -0.1778)
						)
						(arc
							(start -0.2794 0.1778)
							(mid -0.249642 0.249642)
							(end -0.1778 0.2794)
						)
						(arc
							(start 0.1778 0.2794)
							(mid 0.249642 0.249642)
							(end 0.2794 0.1778)
						)
						(arc
							(start 0.2794 -0.1778)
							(mid 0.249642 -0.249642)
							(end 0.1778 -0.2794)
						)
					)
					(width 0)
					(fill yes)
				)
			)
		)
	)
	(footprint ""
		(layer "F.Cu")
		(at 33.4518 -6.096 90)
		(property "Reference" "R20"
			(at 0 0 90)
			(layer "F.SilkS")
			(hide yes)
			(effects
				(font
					(size 1.27 1.27)
				)
			)
		)
		(property "Value" "0R2J-2-GP"
			(at 0.064008 -3.993896 90)
			(unlocked yes)
			(layer "F.Fab")
			(hide yes)
			(effects
				(font
					(size 1.016 1.016)
					(thickness 0.1524)
				)
			)
		)
		(property "Device Type" "R402H16"
			(at 0.064008 -5.517896 90)
			(unlocked yes)
			(layer "F.Fab")
			(hide yes)
			(effects
				(font
					(size 1.016 1.016)
					(thickness 0.1524)
				)
			)
		)
		(duplicate_pad_numbers_are_jumpers no)
		(fp_line
			(start 0.508 -0.9398)
			(end -0.508 -0.9398)
			(stroke
				(width 0.1524)
				(type default)
			)
			(layer "F.SilkS")
		)
		(fp_line
			(start -0.508 -0.9398)
			(end -0.508 0.9398)
			(stroke
				(width 0.1524)
				(type default)
			)
			(layer "F.SilkS")
		)
		(fp_rect
			(start -0.508 0.9398)
			(end 0.508 -0.9398)
			(stroke
				(width 0)
				(type default)
			)
			(fill no)
			(layer "F.CrtYd")
		)
		(fp_rect
			(start -0.508 0.9398)
			(end 0.508 -0.9398)
			(stroke
				(width 0)
				(type default)
			)
			(fill no)
			(layer "F.Fab")
		)
		(pad "1" smd custom
			(at 0 -0.4445 90)
			(size 0.1397 0.1397)
			(layers "F.Cu" "F.Mask" "F.Paste")
			(net "D_FLIP_PRE_B#")
			(options
				(clearance outline)
				(anchor circle)
			)
			(primitives
				(gr_poly
					(pts
						(arc
							(start -0.1778 -0.2794)
							(mid -0.249642 -0.249642)
							(end -0.2794 -0.1778)
						)
						(arc
							(start -0.2794 0.1778)
							(mid -0.249642 0.249642)
							(end -0.1778 0.2794)
						)
						(arc
							(start 0.1778 0.2794)
							(mid 0.249642 0.249642)
							(end 0.2794 0.1778)
						)
						(arc
							(start 0.2794 -0.1778)
							(mid 0.249642 -0.249642)
							(end 0.1778 -0.2794)
						)
					)
					(width 0)
					(fill yes)
				)
			)
		)
		(pad "2" smd custom
			(at 0 0.4445 90)
			(size 0.1397 0.1397)
			(layers "F.Cu" "F.Mask" "F.Paste")
			(net "P3V3_STBY_B")
			(options
				(clearance outline)
				(anchor circle)
			)
			(primitives
				(gr_poly
					(pts
						(arc
							(start -0.1778 -0.2794)
							(mid -0.249642 -0.249642)
							(end -0.2794 -0.1778)
						)
						(arc
							(start -0.2794 0.1778)
							(mid -0.249642 0.249642)
							(end -0.1778 0.2794)
						)
						(arc
							(start 0.1778 0.2794)
							(mid 0.249642 0.249642)
							(end 0.2794 0.1778)
						)
						(arc
							(start 0.2794 -0.1778)
							(mid 0.249642 -0.249642)
							(end 0.1778 -0.2794)
						)
					)
					(width 0)
					(fill yes)
				)
			)
		)
	)
	(footprint ""
		(layer "F.Cu")
		(at 8.5598 -30.4292)
		(property "Reference" "R75"
			(at 0 0 0)
			(layer "F.SilkS")
			(hide yes)
			(effects
				(font
					(size 1.27 1.27)
				)
			)
		)
		(property "Value" "0R2J-2-GP"
			(at 0.064008 -3.993896 0)
			(unlocked yes)
			(layer "F.Fab")
			(hide yes)
			(effects
				(font
					(size 1.016 1.016)
					(thickness 0.1524)
				)
			)
		)
		(property "Device Type" "R402H16"
			(at 0.064008 -5.517896 0)
			(unlocked yes)
			(layer "F.Fab")
			(hide yes)
			(effects
				(font
					(size 1.016 1.016)
					(thickness 0.1524)
				)
			)
		)
		(duplicate_pad_numbers_are_jumpers no)
		(fp_line
			(start -0.508 -0.9398)
			(end -0.508 0.9398)
			(stroke
				(width 0.1524)
				(type default)
			)
			(layer "F.SilkS")
		)
		(fp_line
			(start 0.508 -0.9398)
			(end -0.508 -0.9398)
			(stroke
				(width 0.1524)
				(type default)
			)
			(layer "F.SilkS")
		)
		(fp_rect
			(start -0.508 0.9398)
			(end 0.508 -0.9398)
			(stroke
				(width 0)
				(type default)
			)
			(fill no)
			(layer "F.CrtYd")
		)
		(fp_rect
			(start -0.508 0.9398)
			(end 0.508 -0.9398)
			(stroke
				(width 0)
				(type default)
			)
			(fill no)
			(layer "F.Fab")
		)
		(pad "1" smd custom
			(at 0 -0.4445)
			(size 0.1397 0.1397)
			(layers "F.Cu" "F.Mask" "F.Paste")
			(net "SYS_RESET_BTN_A_N")
			(options
				(clearance outline)
				(anchor circle)
			)
			(primitives
				(gr_poly
					(pts
						(arc
							(start -0.1778 -0.2794)
							(mid -0.249642 -0.249642)
							(end -0.2794 -0.1778)
						)
						(arc
							(start -0.2794 0.1778)
							(mid -0.249642 0.249642)
							(end -0.1778 0.2794)
						)
						(arc
							(start 0.1778 0.2794)
							(mid 0.249642 0.249642)
							(end 0.2794 0.1778)
						)
						(arc
							(start 0.2794 -0.1778)
							(mid 0.249642 -0.249642)
							(end 0.1778 -0.2794)
						)
					)
					(width 0)
					(fill yes)
				)
			)
		)
		(pad "2" smd custom
			(at 0 0.4445)
			(size 0.1397 0.1397)
			(layers "F.Cu" "F.Mask" "F.Paste")
			(net "SYS_RESET_BTN_A_N_R")
			(options
				(clearance outline)
				(anchor circle)
			)
			(primitives
				(gr_poly
					(pts
						(arc
							(start -0.1778 -0.2794)
							(mid -0.249642 -0.249642)
							(end -0.2794 -0.1778)
						)
						(arc
							(start -0.2794 0.1778)
							(mid -0.249642 0.249642)
							(end -0.1778 0.2794)
						)
						(arc
							(start 0.1778 0.2794)
							(mid 0.249642 0.249642)
							(end 0.2794 0.1778)
						)
						(arc
							(start 0.2794 -0.1778)
							(mid 0.249642 -0.249642)
							(end 0.1778 -0.2794)
						)
					)
					(width 0)
					(fill yes)
				)
			)
		)
	)
)
